# S9S_MB_2U (Grand Teton) — schematic netlist excerpt (pin names and nets, part order shuffled) for the footprints in the layout excerpt that follows; sources: Cadence DE-HDL packaged netlist, KiCad conversion of 03242023_DA0F0TMBIJ0_F0T_Motherboard_J_brd_V01_OCP.brd

R286  Q_RES  10K 1% CHIP  pkg 0402LF  page 119 : A = P3V3_AUX ; B = FM_CPU0_PROC_ID0

Q96  MOSFET_NCH_DUAL  PJT138K IC  pkg SOT363XD  page 148
  S1  = GND
  G1  = GPU_FPGA_READY
  D2  = GPU_FPGA_READY_ISO
  S2  = GND
  G2  = GPU_FPGA_READY_N
  D1  = GPU_FPGA_READY_N

C702  Q_CAP_DIFFBUS  DIFF BUS_0.22UF 6.3V 20% X6S  pkg C0201  page 177 : \1\ = P5E_CPU1_PE4_TX_C_DN<3> ; \2\ = P5E_CPU1_PE4_TX_DN<3>

(kicad_pcb
	(version 20260206)
	(generator "pcbnew")
	(generator_version "10.0")
	(general
		(thickness 1.6)
		(legacy_teardrops no)
	)
	(paper "A4")
	(title_block
		(title "03242023_DA0F0TMBIJ0_F0T_Motherboard_J_brd_V01_OCP.brd")
		(comment 1 "Grand Teton / footprints 2798-2800 of 6105")
	)
	(layers
		(0 "F.Cu" signal "TOP")
		(4 "In1.Cu" signal "GND")
		(6 "In2.Cu" signal "IN1")
		(8 "In3.Cu" signal "GND1")
		(10 "In4.Cu" signal "IN2")
		(12 "In5.Cu" signal "GND2")
		(14 "In6.Cu" signal "IN3")
		(16 "In7.Cu" signal "GND3")
		(18 "In8.Cu" signal "VCC")
		(20 "In9.Cu" signal "VCC1")
		(22 "In10.Cu" signal "GND4")
		(24 "In11.Cu" signal "IN4")
		(26 "In12.Cu" signal "GND5")
		(28 "In13.Cu" signal "IN5")
		(30 "In14.Cu" signal "GND6")
		(32 "In15.Cu" signal "IN6")
		(34 "In16.Cu" signal "GND7")
		(2 "B.Cu" signal "BOTTOM")
		(9 "F.Adhes" user "F.Adhesive")
		(11 "B.Adhes" user "B.Adhesive")
		(13 "F.Paste" user "Package Geometry/Pastemask Top")
		(15 "B.Paste" user "Package Geometry/Pastemask Bottom")
		(5 "F.SilkS" user "Ref Des/Silkscreen Top")
		(7 "B.SilkS" user "Ref Des/Silkscreen Bottom")
		(1 "F.Mask" user "Board Geometry/Soldermask Top")
		(3 "B.Mask" user "Board Geometry/Soldermask Bottom")
		(17 "Dwgs.User" user "User.Drawings")
		(19 "Cmts.User" user "User.Comments")
		(21 "Eco1.User" user "User.Eco1")
		(23 "Eco2.User" user "User.Eco2")
		(25 "Edge.Cuts" user "Board Geometry/Outline")
		(27 "Margin" user)
		(31 "F.CrtYd" user "Package Geometry/Place Bound Top")
		(29 "B.CrtYd" user "Package Geometry/Place Bound Bottom")
		(35 "F.Fab" user "Ref Des/Assembly Top")
		(33 "B.Fab" user "Ref Des/Assembly Bottom")
	)
	(footprint ""
		(layer "F.Cu")
		(at 28.081732 -403.695408)
		(property "Reference" "Q96"
			(at 1.97358 1.620012 0)
			(unlocked yes)
			(layer "F.SilkS")
			(effects
				(font
					(size 0.7874 0.5842)
					(thickness 0.1524)
				)
				(justify left)
			)
		)
		(property "Value" ""
			(at 0 0 0)
			(layer "F.Fab")
			(effects
				(font
					(size 1.27 1.27)
				)
			)
		)
		(duplicate_pad_numbers_are_jumpers no)
		(fp_line
			(start -1.332738 -1.100074)
			(end -0.4826 -1.100074)
			(stroke
				(width 0.1524)
				(type default)
			)
			(layer "F.SilkS")
		)
		(fp_line
			(start -1.332738 1.100074)
			(end -1.332738 -1.100074)
			(stroke
				(width 0.1524)
				(type default)
			)
			(layer "F.SilkS")
		)
		(fp_line
			(start -0.4826 -1.100074)
			(end 0 -0.541274)
			(stroke
				(width 0.1524)
				(type default)
			)
			(layer "F.SilkS")
		)
		(fp_line
			(start 0 -0.541274)
			(end 0.4826 -1.100074)
			(stroke
				(width 0.1524)
				(type default)
			)
			(layer "F.SilkS")
		)
		(fp_line
			(start 0.4826 -1.100074)
			(end 1.332738 -1.100074)
			(stroke
				(width 0.1524)
				(type default)
			)
			(layer "F.SilkS")
		)
		(fp_line
			(start 1.332738 -1.100074)
			(end 1.332738 1.100074)
			(stroke
				(width 0.1524)
				(type default)
			)
			(layer "F.SilkS")
		)
		(fp_line
			(start 1.332738 1.100074)
			(end -1.332738 1.100074)
			(stroke
				(width 0.1524)
				(type default)
			)
			(layer "F.SilkS")
		)
		(fp_poly
			(pts
				(xy -1.848612 -1.41478) (xy -1.600454 -0.670306) (xy -2.344928 -0.918464)
			)
			(stroke
				(width 0)
				(type default)
			)
			(fill yes)
			(layer "F.SilkS")
		)
		(fp_line
			(start -0.674878 -1.100074)
			(end 0.674878 -1.100074)
			(stroke
				(width 0.1)
				(type default)
			)
			(layer "F.Fab")
		)
		(fp_line
			(start -0.674878 1.100074)
			(end -0.674878 -1.100074)
			(stroke
				(width 0.1)
				(type default)
			)
			(layer "F.Fab")
		)
		(fp_line
			(start 0.674878 -1.100074)
			(end 0.674878 1.100074)
			(stroke
				(width 0.1)
				(type default)
			)
			(layer "F.Fab")
		)
		(fp_line
			(start 0.674878 1.100074)
			(end -0.674878 1.100074)
			(stroke
				(width 0.1)
				(type default)
			)
			(layer "F.Fab")
		)
		(fp_poly
			(pts
				(xy -2.2352 -0.298958) (xy -2.2352 -1.001014) (xy -1.533144 -0.649986)
			)
			(stroke
				(width 0)
				(type default)
			)
			(fill yes)
			(layer "F.Fab")
		)
		(pad "1" smd rect
			(at -0.94996 -0.649986 90)
			(size 0.4318 0.508)
			(layers "F.Cu" "F.Mask" "F.Paste")
			(net "GND")
		)
		(pad "2" smd rect
			(at -0.94996 0 90)
			(size 0.4318 0.508)
			(layers "F.Cu" "F.Mask" "F.Paste")
			(net "GPU_FPGA_READY")
		)
		(pad "3" smd rect
			(at -0.94996 0.649986 90)
			(size 0.4318 0.508)
			(layers "F.Cu" "F.Mask" "F.Paste")
			(net "GPU_FPGA_READY_ISO")
		)
		(pad "4" smd rect
			(at 0.94996 0.649986 90)
			(size 0.4318 0.508)
			(layers "F.Cu" "F.Mask" "F.Paste")
			(net "GND")
		)
		(pad "5" smd rect
			(at 0.94996 0 90)
			(size 0.4318 0.508)
			(layers "F.Cu" "F.Mask" "F.Paste")
			(net "GPU_FPGA_READY_N")
		)
		(pad "6" smd rect
			(at 0.94996 -0.649986 90)
			(size 0.4318 0.508)
			(layers "F.Cu" "F.Mask" "F.Paste")
			(net "GPU_FPGA_READY_N")
		)
	)
	(footprint ""
		(layer "F.Cu")
		(at 189.28588 -130.266948 -90)
		(property "Reference" "R286"
			(at 0 0 270)
			(layer "F.SilkS")
			(hide yes)
			(effects
				(font
					(size 1.27 1.27)
				)
			)
		)
		(property "Value" ""
			(at 0 0 270)
			(layer "F.Fab")
			(effects
				(font
					(size 1.27 1.27)
				)
			)
		)
		(duplicate_pad_numbers_are_jumpers no)
		(fp_line
			(start -0.7874 0.4064)
			(end -0.7874 -0.4064)
			(stroke
				(width 0.1524)
				(type default)
			)
			(layer "F.SilkS")
		)
		(fp_line
			(start 0.7874 0.4064)
			(end -0.7874 0.4064)
			(stroke
				(width 0.1524)
				(type default)
			)
			(layer "F.SilkS")
		)
		(fp_line
			(start -0.7874 -0.4064)
			(end 0.7874 -0.4064)
			(stroke
				(width 0.1524)
				(type default)
			)
			(layer "F.SilkS")
		)
		(fp_line
			(start 0.7874 -0.4064)
			(end 0.7874 0.4064)
			(stroke
				(width 0.1524)
				(type default)
			)
			(layer "F.SilkS")
		)
		(fp_line
			(start -0.67945 0.3048)
			(end -0.67945 -0.305054)
			(stroke
				(width 0.1)
				(type default)
			)
			(layer "F.Fab")
		)
		(fp_line
			(start -0.12065 0.3048)
			(end -0.67945 0.3048)
			(stroke
				(width 0.1)
				(type default)
			)
			(layer "F.Fab")
		)
		(fp_line
			(start 0.120396 0.3048)
			(end 0.120396 0.2794)
			(stroke
				(width 0.1)
				(type default)
			)
			(layer "F.Fab")
		)
		(fp_line
			(start 0.67945 0.3048)
			(end 0.120396 0.3048)
			(stroke
				(width 0.1)
				(type default)
			)
			(layer "F.Fab")
		)
		(fp_line
			(start -0.12065 0.2794)
			(end -0.12065 0.3048)
			(stroke
				(width 0.1)
				(type default)
			)
			(layer "F.Fab")
		)
		(fp_line
			(start 0.120396 0.2794)
			(end -0.12065 0.2794)
			(stroke
				(width 0.1)
				(type default)
			)
			(layer "F.Fab")
		)
		(fp_line
			(start -0.12065 -0.2794)
			(end 0.12065 -0.2794)
			(stroke
				(width 0.1)
				(type default)
			)
			(layer "F.Fab")
		)
		(fp_line
			(start 0.12065 -0.2794)
			(end 0.12065 -0.3048)
			(stroke
				(width 0.1)
				(type default)
			)
			(layer "F.Fab")
		)
		(fp_line
			(start 0.12065 -0.3048)
			(end 0.67945 -0.3048)
			(stroke
				(width 0.1)
				(type default)
			)
			(layer "F.Fab")
		)
		(fp_line
			(start 0.67945 -0.3048)
			(end 0.67945 0.3048)
			(stroke
				(width 0.1)
				(type default)
			)
			(layer "F.Fab")
		)
		(fp_line
			(start -0.67945 -0.305054)
			(end -0.12065 -0.305054)
			(stroke
				(width 0.1)
				(type default)
			)
			(layer "F.Fab")
		)
		(fp_line
			(start -0.12065 -0.305054)
			(end -0.12065 -0.2794)
			(stroke
				(width 0.1)
				(type default)
			)
			(layer "F.Fab")
		)
		(pad "1" smd circle
			(at -0.40005 0 270)
			(size 0 0)
			(layers "F.Cu" "F.Mask" "F.Paste")
			(net "P3V3_AUX")
		)
		(pad "2" smd circle
			(at 0.40005 0 270)
			(size 0 0)
			(layers "F.Cu" "F.Mask" "F.Paste")
			(net "FM_CPU0_PROC_ID0")
		)
	)
	(footprint ""
		(layer "F.Cu")
		(at 58.490358 -408.517344 -90)
		(property "Reference" "C702"
			(at 0 0 270)
			(layer "F.SilkS")
			(hide yes)
			(effects
				(font
					(size 1.27 1.27)
				)
			)
		)
		(property "Value" ""
			(at 0 0 270)
			(layer "F.Fab")
			(effects
				(font
					(size 1.27 1.27)
				)
			)
		)
		(duplicate_pad_numbers_are_jumpers no)
		(fp_line
			(start -0.299974 0.150114)
			(end -0.299974 -0.150114)
			(stroke
				(width 0.1)
				(type default)
			)
			(layer "F.Fab")
		)
		(fp_line
			(start 0.299974 0.150114)
			(end -0.299974 0.150114)
			(stroke
				(width 0.1)
				(type default)
			)
			(layer "F.Fab")
		)
		(fp_line
			(start -0.299974 -0.150114)
			(end 0.299974 -0.150114)
			(stroke
				(width 0.1)
				(type default)
			)
			(layer "F.Fab")
		)
		(fp_line
			(start 0.299974 -0.150114)
			(end 0.299974 0.150114)
			(stroke
				(width 0.1)
				(type default)
			)
			(layer "F.Fab")
		)
		(pad "1" smd rect
			(at -0.2667 0 270)
			(size 0.3048 0.381)
			(layers "F.Cu" "F.Mask" "F.Paste")
			(net "P5E_CPU1_PE4_TX_C_DN<3>")
		)
		(pad "2" smd rect
			(at 0.2667 0 270)
			(size 0.3048 0.381)
			(layers "F.Cu" "F.Mask" "F.Paste")
			(net "P5E_CPU1_PE4_TX_DN<3>")
		)
	)
)
